#ISCELL
  mstr_misc dns *
  *
#ISCELL
  pure_quanta quanta_title_block_c *
  *
#ISCELL
  pure_quanta_power vcc_core *
  page463_i10
#ISCELL
  pure_quanta_power universal_gnd *
  page463_i11
#ISCELL
  pure_quanta_power universal_gnd *
  page463_i12
#CELL
  pure_quanta q_res *
  page463_i13
#ISCELL
  pure_quanta_power universal_gnd *
  page463_i14
#CELL
  pure_quanta q_res *
  page463_i15
#ISCELL
  pure_quanta_power universal_gnd *
  page463_i16
#CELL
  pure_quanta pt5161lrs *
  page463_i17
#CELL
  pure_quanta q_res *
  page463_i18
#CELL
  pure_quanta q_res *
  page463_i19
#ISCELL
  pure_quanta_power p1v0 *
  page463_i2
#ISCELL
  pure_quanta_power universal_gnd *
  page463_i3
#CELL
  pure_quanta pt5161lrs *
  page463_i5
#ISCELL
  pure_quanta_power p1v0 *
  page463_i6
#ISCELL
  pure_quanta_power p1v0 *
  page463_i7
#ISCELL
  pure_quanta_power p1v0 *
  page463_i8
#ISCELL
  pure_quanta_power vcc_core *
  page463_i9
